(kicad_pcb
	(version 20241229)
	(generator "pcbnew")
	(generator_version "9.0")
	(general
		(thickness 1.552)
		(legacy_teardrops no)
	)
	(paper "A4")
	(title_block
		(date "2023-07-25")
		(rev "1.1.4")
		(comment 9 "footprints 133-136 of 379")
	)
	(layers
		(0 "F.Cu" signal)
		(4 "In1.Cu" signal)
		(6 "In2.Cu" signal)
		(8 "In3.Cu" signal)
		(10 "In4.Cu" signal)
		(12 "In5.Cu" signal)
		(14 "In6.Cu" signal)
		(2 "B.Cu" signal)
		(9 "F.Adhes" user "F.Adhesive")
		(11 "B.Adhes" user "B.Adhesive")
		(13 "F.Paste" user)
		(15 "B.Paste" user)
		(5 "F.SilkS" user "F.Silkscreen")
		(7 "B.SilkS" user "B.Silkscreen")
		(1 "F.Mask" user)
		(3 "B.Mask" user)
		(17 "Dwgs.User" user "User.Drawings")
		(19 "Cmts.User" user "User.Comments")
		(21 "Eco1.User" user "User.Eco1")
		(23 "Eco2.User" user "User.Eco2")
		(25 "Edge.Cuts" user)
		(27 "Margin" user)
		(31 "F.CrtYd" user "F.Courtyard")
		(29 "B.CrtYd" user "B.Courtyard")
		(35 "F.Fab" user)
		(33 "B.Fab" user)
	)
	(footprint "antmicro-footprints:R_0402_1005Metric"
		(layer "F.Cu")
		(at 99.94 115.185 90)
		(descr "Resistor SMD 0402")
		(tags "resistor SMD 0402")
		(property "Reference" "R92"
			(at 0.895 0.39 90)
			(layer "F.SilkS")
			(effects
				(font
					(size 0.65 0.65)
					(thickness 0.15)
				)
				(justify left bottom)
			)
		)
		(property "Value" "R_0R_0402"
			(at 0 1.4 90)
			(layer "F.Fab")
			(hide yes)
			(effects
				(font
					(size 0.7 0.7)
					(thickness 0.15)
				)
				(justify left bottom)
			)
		)
		(property "Datasheet" "https://industrial.panasonic.com/cdbs/www-data/pdf/RDA0000/AOA0000C301.pdf"
			(at 0 0 90)
			(layer "F.Fab")
			(hide yes)
			(effects
				(font
					(size 1.27 1.27)
					(thickness 0.15)
				)
			)
		)
		(property "Description" "SMD Chip Resistor, Jumper, 0 ohm, 100 mW, 0402 [1005 Metric], Thick Film, General Purpose"
			(at 0 0 90)
			(layer "F.Fab")
			(hide yes)
			(effects
				(font
					(size 1.27 1.27)
					(thickness 0.15)
				)
			)
		)
		(property "Author" "Antmicro"
			(at 215.125 15.245 0)
			(layer "F.Fab")
			(hide yes)
			(effects
				(font
					(size 1 1)
					(thickness 0.15)
				)
			)
		)
		(property "Current" "1A"
			(at 215.125 15.245 0)
			(layer "F.Fab")
			(hide yes)
			(effects
				(font
					(size 1 1)
					(thickness 0.15)
				)
			)
		)
		(property "License" "Apache-2.0"
			(at 215.125 15.245 0)
			(layer "F.Fab")
			(hide yes)
			(effects
				(font
					(size 1 1)
					(thickness 0.15)
				)
			)
		)
		(property "MPN" "ERJ2GE0R00X"
			(at 215.125 15.245 0)
			(layer "F.Fab")
			(hide yes)
			(effects
				(font
					(size 1 1)
					(thickness 0.15)
				)
			)
		)
		(property "Manufacturer" "Panasonic"
			(at 215.125 15.245 0)
			(layer "F.Fab")
			(hide yes)
			(effects
				(font
					(size 1 1)
					(thickness 0.15)
				)
			)
		)
		(property "Tolerance" "~"
			(at 215.125 15.245 0)
			(layer "F.Fab")
			(hide yes)
			(effects
				(font
					(size 1 1)
					(thickness 0.15)
				)
			)
		)
		(property "Val" "0R"
			(at 215.125 15.245 0)
			(layer "F.Fab")
			(hide yes)
			(effects
				(font
					(size 1 1)
					(thickness 0.15)
				)
			)
		)
		(sheetname "/FPGA/")
		(sheetfile "fpga.kicad_sch")
		(attr smd)
		(fp_rect
			(start -0.925 -0.47)
			(end 0.925 0.47)
			(stroke
				(width 0.05)
				(type default)
			)
			(fill no)
			(layer "F.CrtYd")
		)
		(fp_rect
			(start -0.5 -0.25)
			(end 0.5 0.25)
			(stroke
				(width 0.15)
				(type solid)
			)
			(fill no)
			(layer "F.Fab")
		)
		(fp_text user "Author: Antmicro"
			(at -0.95 4.169 90)
			(layer "F.Fab")
			(effects
				(font
					(size 0.7 0.7)
					(thickness 0.15)
				)
				(justify left bottom)
			)
		)
		(fp_text user "${REFERENCE}"
			(at -0.95 3.168 90)
			(layer "F.Fab")
			(effects
				(font
					(size 0.7 0.7)
					(thickness 0.15)
				)
				(justify left bottom)
			)
		)
		(fp_text user "License: Apache-2.0"
			(at -0.95 5.169 90)
			(layer "F.Fab")
			(effects
				(font
					(size 0.7 0.7)
					(thickness 0.15)
				)
				(justify left bottom)
			)
		)
		(pad "1" smd roundrect
			(at -0.48 0 90)
			(size 0.59 0.64)
			(layers "F.Cu" "F.Mask" "F.Paste")
			(roundrect_rratio 0.25)
			(net 135 "Net-(J7-Pad4)")
			(pintype "passive")
		)
		(pad "2" smd roundrect
			(at 0.48 0 90)
			(size 0.59 0.64)
			(layers "F.Cu" "F.Mask" "F.Paste")
			(roundrect_rratio 0.25)
			(net 170 "TCK")
			(pintype "passive")
		)
	)
	(footprint "antmicro-footprints:R_0805_2012Metric"
		(layer "F.Cu")
		(at 147.49 63.35 -90)
		(property "Reference" "R16"
			(at 0.19 -1.74 90)
			(layer "F.SilkS")
			(effects
				(font
					(size 0.65 0.65)
					(thickness 0.15)
				)
				(justify right bottom)
			)
		)
		(property "Value" "R_0R_0805"
			(at 0 1.8 90)
			(layer "F.Fab")
			(hide yes)
			(effects
				(font
					(size 0.7 0.7)
					(thickness 0.15)
				)
				(justify right bottom)
			)
		)
		(property "Datasheet" "https://www.vishay.com/docs/20035/dcrcwe3.pdf"
			(at 0 0 270)
			(layer "F.Fab")
			(hide yes)
			(effects
				(font
					(size 1.27 1.27)
					(thickness 0.15)
				)
			)
		)
		(property "Description" "Zero Ohm Resistor, Jumper, 0805 [2012 Metric], Thick Film, 125 mW, 2.5 A, Surface Mount Device"
			(at 0 0 270)
			(layer "F.Fab")
			(hide yes)
			(effects
				(font
					(size 1.27 1.27)
					(thickness 0.15)
				)
			)
		)
		(property "Author" "Antmicro"
			(at 84.14 210.84 0)
			(layer "F.Fab")
			(hide yes)
			(effects
				(font
					(size 1 1)
					(thickness 0.15)
				)
			)
		)
		(property "Current" "2.5A"
			(at 84.14 210.84 0)
			(layer "F.Fab")
			(hide yes)
			(effects
				(font
					(size 1 1)
					(thickness 0.15)
				)
			)
		)
		(property "License" "Apache-2.0"
			(at 84.14 210.84 0)
			(layer "F.Fab")
			(hide yes)
			(effects
				(font
					(size 1 1)
					(thickness 0.15)
				)
			)
		)
		(property "MPN" "CRCW08050000Z0EA"
			(at 84.14 210.84 0)
			(layer "F.Fab")
			(hide yes)
			(effects
				(font
					(size 1 1)
					(thickness 0.15)
				)
			)
		)
		(property "Manufacturer" "Vishay"
			(at 84.14 210.84 0)
			(layer "F.Fab")
			(hide yes)
			(effects
				(font
					(size 1 1)
					(thickness 0.15)
				)
			)
		)
		(property "Tolerance" "~"
			(at 84.14 210.84 0)
			(layer "F.Fab")
			(hide yes)
			(effects
				(font
					(size 1 1)
					(thickness 0.15)
				)
			)
		)
		(property "Val" "0R"
			(at 84.14 210.84 0)
			(layer "F.Fab")
			(hide yes)
			(effects
				(font
					(size 1 1)
					(thickness 0.15)
				)
			)
		)
		(sheetname "/Power Supply/")
		(sheetfile "supply.kicad_sch")
		(attr smd)
		(fp_line
			(start -0.32 0.699)
			(end 0.28 0.699)
			(stroke
				(width 0.15)
				(type solid)
			)
			(layer "F.SilkS")
		)
		(fp_line
			(start -0.3 -0.701)
			(end 0.298 -0.701)
			(stroke
				(width 0.15)
				(type solid)
			)
			(layer "F.SilkS")
		)
		(fp_rect
			(start 1.95 -0.9)
			(end -1.95 0.9)
			(stroke
				(width 0.05)
				(type default)
			)
			(fill no)
			(layer "F.CrtYd")
		)
		(fp_line
			(start -0.951 0.68)
			(end 0.949 0.68)
			(stroke
				(width 0.15)
				(type solid)
			)
			(layer "F.Fab")
		)
		(fp_line
			(start -0.951 -0.677)
			(end -0.951 0.675)
			(stroke
				(width 0.15)
				(type solid)
			)
			(layer "F.Fab")
		)
		(fp_line
			(start 0.949 -0.677)
			(end 0.949 0.675)
			(stroke
				(width 0.15)
				(type solid)
			)
			(layer "F.Fab")
		)
		(fp_line
			(start -0.951 -0.682)
			(end 0.949 -0.682)
			(stroke
				(width 0.15)
				(type solid)
			)
			(layer "F.Fab")
		)
		(fp_text user "Author: Antmicro"
			(at -1.9 4.4 270)
			(layer "F.Fab")
			(effects
				(font
					(size 0.7 0.7)
					(thickness 0.15)
				)
				(justify left bottom)
			)
		)
		(fp_text user "License: Apache-2.0"
			(at -1.9 5.75 270)
			(layer "F.Fab")
			(effects
				(font
					(size 0.7 0.7)
					(thickness 0.15)
				)
				(justify left bottom)
			)
		)
		(fp_text user "${REFERENCE}"
			(at -1.9 3.1 270)
			(layer "F.Fab")
			(effects
				(font
					(size 0.7 0.7)
					(thickness 0.15)
				)
				(justify left bottom)
			)
		)
		(pad "1" smd roundrect
			(at -1.1 0 270)
			(size 1.2 1.3)
			(layers "F.Cu" "F.Mask" "F.Paste")
			(roundrect_rratio 0.25)
			(net 327 "/Power Supply/5V_1V5_IN")
			(pintype "passive")
		)
		(pad "2" smd roundrect
			(at 1.1 0 270)
			(size 1.2 1.3)
			(layers "F.Cu" "F.Mask" "F.Paste")
			(roundrect_rratio 0.25)
			(net 14 "+5V")
			(pintype "passive")
		)
	)
	(footprint "antmicro-footprints:TP_SMD_0.75mm"
		(layer "F.Cu")
		(at 152.7908 72.64 90)
		(property "Reference" "TP2"
			(at 0.5 0.3392 90)
			(layer "F.SilkS")
			(effects
				(font
					(size 0.65 0.65)
					(thickness 0.15)
				)
				(justify left bottom)
			)
		)
		(property "Value" "TP_0.75mm_SMD"
			(at 0 1.2 90)
			(layer "F.Fab")
			(hide yes)
			(effects
				(font
					(size 0.7 0.7)
					(thickness 0.15)
				)
				(justify left bottom)
			)
		)
		(property "Description" "SMT test point"
			(at 0 0 90)
			(layer "F.Fab")
			(hide yes)
			(effects
				(font
					(size 1.27 1.27)
					(thickness 0.15)
				)
			)
		)
		(property "Author" "Antmicro"
			(at 225.4308 -80.1508 0)
			(layer "F.Fab")
			(hide yes)
			(effects
				(font
					(size 1 1)
					(thickness 0.15)
				)
			)
		)
		(property "License" "Apache-2.0"
			(at 225.4308 -80.1508 0)
			(layer "F.Fab")
			(hide yes)
			(effects
				(font
					(size 1 1)
					(thickness 0.15)
				)
			)
		)
		(property "MPN" ""
			(at 225.4308 -80.1508 0)
			(layer "F.Fab")
			(hide yes)
			(effects
				(font
					(size 1 1)
					(thickness 0.15)
				)
			)
		)
		(property "Manufacturer" ""
			(at 225.4308 -80.1508 0)
			(layer "F.Fab")
			(hide yes)
			(effects
				(font
					(size 1 1)
					(thickness 0.15)
				)
			)
		)
		(sheetname "/Power Supply/")
		(sheetfile "supply.kicad_sch")
		(attr exclude_from_pos_files)
		(fp_circle
			(center 0 0)
			(end 0.475 0)
			(stroke
				(width 0.05)
				(type default)
			)
			(fill no)
			(layer "F.CrtYd")
		)
		(fp_text user "${REFERENCE}"
			(at -0.4 2.7 90)
			(layer "F.Fab")
			(effects
				(font
					(size 0.7 0.7)
					(thickness 0.15)
				)
				(justify left bottom)
			)
		)
		(fp_text user "Author: Antmicro"
			(at -0.4 3.901 90)
			(layer "F.Fab")
			(effects
				(font
					(size 0.7 0.7)
					(thickness 0.15)
				)
				(justify left bottom)
			)
		)
		(fp_text user "License: Apache-2.0"
			(at -0.4 5.101 90)
			(layer "F.Fab")
			(effects
				(font
					(size 0.7 0.7)
					(thickness 0.15)
				)
				(justify left bottom)
			)
		)
		(pad "1" smd circle
			(at 0 0 90)
			(size 0.75 0.75)
			(layers "F.Cu" "F.Mask")
			(net 14 "+5V")
			(pinfunction "1")
			(pintype "passive")
		)
	)
	(footprint "antmicro-footprints:TP_SMD_0.75mm"
		(layer "F.Cu")
		(at 100.25 68.25)
		(property "Reference" "TP27"
			(at 0.53 0.39 0)
			(layer "F.SilkS")
			(effects
				(font
					(size 0.65 0.65)
					(thickness 0.15)
				)
				(justify left bottom)
			)
		)
		(property "Value" "TP_0.75mm_SMD"
			(at 0 1.2 0)
			(layer "F.Fab")
			(hide yes)
			(effects
				(font
					(size 0.7 0.7)
					(thickness 0.15)
				)
				(justify left bottom)
			)
		)
		(property "Description" "SMT test point"
			(at 0 0 0)
			(layer "F.Fab")
			(hide yes)
			(effects
				(font
					(size 1.27 1.27)
					(thickness 0.15)
				)
			)
		)
		(property "Author" "Antmicro"
			(at 0 0 0)
			(layer "F.Fab")
			(hide yes)
			(effects
				(font
					(size 1 1)
					(thickness 0.15)
				)
			)
		)
		(property "License" "Apache-2.0"
			(at 0 0 0)
			(layer "F.Fab")
			(hide yes)
			(effects
				(font
					(size 1 1)
					(thickness 0.15)
				)
			)
		)
		(property "MPN" ""
			(at 0 0 0)
			(layer "F.Fab")
			(hide yes)
			(effects
				(font
					(size 1 1)
					(thickness 0.15)
				)
			)
		)
		(property "Manufacturer" ""
			(at 0 0 0)
			(layer "F.Fab")
			(hide yes)
			(effects
				(font
					(size 1 1)
					(thickness 0.15)
				)
			)
		)
		(sheetname "/SDI/")
		(sheetfile "sdi.kicad_sch")
		(attr exclude_from_pos_files)
		(fp_circle
			(center 0 0)
			(end 0.475 0)
			(stroke
				(width 0.05)
				(type default)
			)
			(fill no)
			(layer "F.CrtYd")
		)
		(fp_text user "License: Apache-2.0"
			(at -0.4 5.101 0)
			(layer "F.Fab")
			(effects
				(font
					(size 0.7 0.7)
					(thickness 0.15)
				)
				(justify left bottom)
			)
		)
		(fp_text user "Author: Antmicro"
			(at -0.4 3.901 0)
			(layer "F.Fab")
			(effects
				(font
					(size 0.7 0.7)
					(thickness 0.15)
				)
				(justify left bottom)
			)
		)
		(fp_text user "${REFERENCE}"
			(at -0.4 2.7 0)
			(layer "F.Fab")
			(effects
				(font
					(size 0.7 0.7)
					(thickness 0.15)
				)
				(justify left bottom)
			)
		)
		(pad "1" smd circle
			(at 0 0)
			(size 0.75 0.75)
			(layers "F.Cu" "F.Mask")
			(net 218 "/SDI/SDI_STAT4")
			(pinfunction "1")
			(pintype "passive")
		)
	)
)
